# BARRELEYE_G2-BPX24-EVT-HW-EBOM-X00_20161124-add_2nd_source_X09-20161207-Final.xls — POP_GA (bom)
| FOXCONN TECHNOLOGY GROUP |  |  |  |  |  |  |  |  |  |  |  |  |
| BILL OF MATERIAL |  |  |  |  |  |  |  |  |  |  |  |  |
| REV OF  BOM |  | CUSTOMER | RACKSPACE |  | CUSTOMER P/N |  | PRODUCT CODE |  | PWA  REV |  | DATE |  |
| Sourcing (Single/Sole/Multi) | Critical Commodity (Y or N) | Component Class (1, 2, other) | Customer PSL (Y or N) | Item Number | Foxconn P/N | Customer P/N | Part Description | Manufacturer  Full Name | Manufacturer  Part Number | Qty | RoHS Status | Location |
